# T6G (Grand Teton) — schematic netlist excerpt (pin names and nets, part order shuffled) for the footprints in the layout excerpt that follows; sources: Cadence DE-HDL packaged netlist, KiCad conversion of 04192023_DAF0TMB3IC0_F0TG_MB_C_brd_V02_OCP.brd

C6644  Q_CAP_DIFFBUS  DIFF BUS_0.22UF 6.3V 20% X6S  pkg C0201  page 319 : \1\ = P5E_CPU1_P0_TX_BUF_C_DN<7> ; \2\ = P5E_CPU1_P0_TX_BUF_DN<7>
R3301  Q_RES  33.2 1% CHIP  pkg 0402LF  page 144 : A = M2_0_PEWAKE_R_N ; B = M2_0_PEWAKE_N
R1038  Q_RES  0 5% CHIP  pkg 0402LF  page 145 : A = FM_LED_ACTIVE_E1S_0_R_BUF ; B = FM_LED_ACTIVE_E1S_0_BUF

(kicad_pcb
	(version 20260206)
	(generator "pcbnew")
	(generator_version "10.0")
	(general
		(thickness 1.6)
		(legacy_teardrops no)
	)
	(paper "A4")
	(title_block
		(title "04192023_DAF0TMB3IC0_F0TG_MB_C_brd_V02_OCP.brd")
		(comment 1 "Grand Teton / footprints 474-476 of 8354")
	)
	(layers
		(0 "F.Cu" signal "TOP")
		(4 "In1.Cu" signal "GND")
		(6 "In2.Cu" signal "IN1")
		(8 "In3.Cu" signal "GND1")
		(10 "In4.Cu" signal "IN2")
		(12 "In5.Cu" signal "GND2")
		(14 "In6.Cu" signal "IN3")
		(16 "In7.Cu" signal "GND3")
		(18 "In8.Cu" signal "VCC")
		(20 "In9.Cu" signal "VCC1")
		(22 "In10.Cu" signal "GND4")
		(24 "In11.Cu" signal "IN4")
		(26 "In12.Cu" signal "GND5")
		(28 "In13.Cu" signal "IN5")
		(30 "In14.Cu" signal "GND6")
		(32 "In15.Cu" signal "IN6")
		(34 "In16.Cu" signal "GND7")
		(2 "B.Cu" signal "BOTTOM")
		(9 "F.Adhes" user "F.Adhesive")
		(11 "B.Adhes" user "B.Adhesive")
		(13 "F.Paste" user "Package Geometry/Pastemask Top")
		(15 "B.Paste" user "Package Geometry/Pastemask Bottom")
		(5 "F.SilkS" user "Ref Des/Silkscreen Top")
		(7 "B.SilkS" user "Ref Des/Silkscreen Bottom")
		(1 "F.Mask" user "Board Geometry/Soldermask Top")
		(3 "B.Mask" user "Board Geometry/Soldermask Bottom")
		(17 "Dwgs.User" user "User.Drawings")
		(19 "Cmts.User" user "User.Comments")
		(21 "Eco1.User" user "User.Eco1")
		(23 "Eco2.User" user "User.Eco2")
		(25 "Edge.Cuts" user "Board Geometry/Outline")
		(27 "Margin" user)
		(31 "F.CrtYd" user "Package Geometry/Place Bound Top")
		(29 "B.CrtYd" user "Package Geometry/Place Bound Bottom")
		(35 "F.Fab" user "Ref Des/Assembly Top")
		(33 "B.Fab" user "Ref Des/Assembly Bottom")
	)
	(footprint ""
		(layer "F.Cu")
		(at 233.748072 -69.560186 -90)
		(property "Reference" "R1038"
			(at 0 0 270)
			(layer "F.SilkS")
			(hide yes)
			(effects
				(font
					(size 1.27 1.27)
				)
			)
		)
		(property "Value" ""
			(at 0 0 270)
			(layer "F.Fab")
			(effects
				(font
					(size 1.27 1.27)
				)
			)
		)
		(duplicate_pad_numbers_are_jumpers no)
		(fp_line
			(start -0.7874 0.4064)
			(end -0.7874 -0.4064)
			(stroke
				(width 0.1524)
				(type default)
			)
			(layer "F.SilkS")
		)
		(fp_line
			(start 0.7874 0.4064)
			(end -0.7874 0.4064)
			(stroke
				(width 0.1524)
				(type default)
			)
			(layer "F.SilkS")
		)
		(fp_line
			(start -0.7874 -0.4064)
			(end 0.7874 -0.4064)
			(stroke
				(width 0.1524)
				(type default)
			)
			(layer "F.SilkS")
		)
		(fp_line
			(start 0.7874 -0.4064)
			(end 0.7874 0.4064)
			(stroke
				(width 0.1524)
				(type default)
			)
			(layer "F.SilkS")
		)
		(fp_line
			(start -0.67945 0.3048)
			(end -0.67945 -0.305054)
			(stroke
				(width 0.1)
				(type default)
			)
			(layer "F.Fab")
		)
		(fp_line
			(start -0.12065 0.3048)
			(end -0.67945 0.3048)
			(stroke
				(width 0.1)
				(type default)
			)
			(layer "F.Fab")
		)
		(fp_line
			(start 0.120396 0.3048)
			(end 0.120396 0.2794)
			(stroke
				(width 0.1)
				(type default)
			)
			(layer "F.Fab")
		)
		(fp_line
			(start 0.67945 0.3048)
			(end 0.120396 0.3048)
			(stroke
				(width 0.1)
				(type default)
			)
			(layer "F.Fab")
		)
		(fp_line
			(start -0.12065 0.2794)
			(end -0.12065 0.3048)
			(stroke
				(width 0.1)
				(type default)
			)
			(layer "F.Fab")
		)
		(fp_line
			(start 0.120396 0.2794)
			(end -0.12065 0.2794)
			(stroke
				(width 0.1)
				(type default)
			)
			(layer "F.Fab")
		)
		(fp_line
			(start -0.12065 -0.2794)
			(end 0.12065 -0.2794)
			(stroke
				(width 0.1)
				(type default)
			)
			(layer "F.Fab")
		)
		(fp_line
			(start 0.12065 -0.2794)
			(end 0.12065 -0.3048)
			(stroke
				(width 0.1)
				(type default)
			)
			(layer "F.Fab")
		)
		(fp_line
			(start 0.12065 -0.3048)
			(end 0.67945 -0.3048)
			(stroke
				(width 0.1)
				(type default)
			)
			(layer "F.Fab")
		)
		(fp_line
			(start 0.67945 -0.3048)
			(end 0.67945 0.3048)
			(stroke
				(width 0.1)
				(type default)
			)
			(layer "F.Fab")
		)
		(fp_line
			(start -0.67945 -0.305054)
			(end -0.12065 -0.305054)
			(stroke
				(width 0.1)
				(type default)
			)
			(layer "F.Fab")
		)
		(fp_line
			(start -0.12065 -0.305054)
			(end -0.12065 -0.2794)
			(stroke
				(width 0.1)
				(type default)
			)
			(layer "F.Fab")
		)
		(pad "1" smd circle
			(at -0.40005 0 270)
			(size 0 0)
			(layers "F.Cu" "F.Mask" "F.Paste")
			(net "FM_LED_ACTIVE_E1S_0_R_BUF")
		)
		(pad "2" smd circle
			(at 0.40005 0 270)
			(size 0 0)
			(layers "F.Cu" "F.Mask" "F.Paste")
			(net "FM_LED_ACTIVE_E1S_0_BUF")
		)
	)
	(footprint ""
		(layer "F.Cu")
		(at 69.211444 -408.517344 -90)
		(property "Reference" "C6644"
			(at 0 0 270)
			(layer "F.SilkS")
			(hide yes)
			(effects
				(font
					(size 1.27 1.27)
				)
			)
		)
		(property "Value" ""
			(at 0 0 270)
			(layer "F.Fab")
			(effects
				(font
					(size 1.27 1.27)
				)
			)
		)
		(duplicate_pad_numbers_are_jumpers no)
		(fp_line
			(start -0.299974 0.150114)
			(end -0.299974 -0.150114)
			(stroke
				(width 0.1)
				(type default)
			)
			(layer "F.Fab")
		)
		(fp_line
			(start 0.299974 0.150114)
			(end -0.299974 0.150114)
			(stroke
				(width 0.1)
				(type default)
			)
			(layer "F.Fab")
		)
		(fp_line
			(start -0.299974 -0.150114)
			(end 0.299974 -0.150114)
			(stroke
				(width 0.1)
				(type default)
			)
			(layer "F.Fab")
		)
		(fp_line
			(start 0.299974 -0.150114)
			(end 0.299974 0.150114)
			(stroke
				(width 0.1)
				(type default)
			)
			(layer "F.Fab")
		)
		(pad "1" smd rect
			(at -0.2667 0 270)
			(size 0.3048 0.381)
			(layers "F.Cu" "F.Mask" "F.Paste")
			(net "P5E_CPU1_P0_TX_BUF_C_DN<7>")
		)
		(pad "2" smd rect
			(at 0.2667 0 270)
			(size 0.3048 0.381)
			(layers "F.Cu" "F.Mask" "F.Paste")
			(net "P5E_CPU1_P0_TX_BUF_DN<7>")
		)
	)
	(footprint ""
		(layer "F.Cu")
		(at 164.544756 -41.112948)
		(property "Reference" "R3301"
			(at 0 0 0)
			(layer "F.SilkS")
			(hide yes)
			(effects
				(font
					(size 1.27 1.27)
				)
			)
		)
		(property "Value" ""
			(at 0 0 0)
			(layer "F.Fab")
			(effects
				(font
					(size 1.27 1.27)
				)
			)
		)
		(duplicate_pad_numbers_are_jumpers no)
		(fp_line
			(start -0.7874 -0.4064)
			(end 0.7874 -0.4064)
			(stroke
				(width 0.1524)
				(type default)
			)
			(layer "F.SilkS")
		)
		(fp_line
			(start -0.7874 0.4064)
			(end -0.7874 -0.4064)
			(stroke
				(width 0.1524)
				(type default)
			)
			(layer "F.SilkS")
		)
		(fp_line
			(start 0.7874 -0.4064)
			(end 0.7874 0.4064)
			(stroke
				(width 0.1524)
				(type default)
			)
			(layer "F.SilkS")
		)
		(fp_line
			(start 0.7874 0.4064)
			(end -0.7874 0.4064)
			(stroke
				(width 0.1524)
				(type default)
			)
			(layer "F.SilkS")
		)
		(fp_line
			(start -0.67945 -0.305054)
			(end -0.12065 -0.305054)
			(stroke
				(width 0.1)
				(type default)
			)
			(layer "F.Fab")
		)
		(fp_line
			(start -0.67945 0.3048)
			(end -0.67945 -0.305054)
			(stroke
				(width 0.1)
				(type default)
			)
			(layer "F.Fab")
		)
		(fp_line
			(start -0.12065 -0.305054)
			(end -0.12065 -0.2794)
			(stroke
				(width 0.1)
				(type default)
			)
			(layer "F.Fab")
		)
		(fp_line
			(start -0.12065 -0.2794)
			(end 0.12065 -0.2794)
			(stroke
				(width 0.1)
				(type default)
			)
			(layer "F.Fab")
		)
		(fp_line
			(start -0.12065 0.2794)
			(end -0.12065 0.3048)
			(stroke
				(width 0.1)
				(type default)
			)
			(layer "F.Fab")
		)
		(fp_line
			(start -0.12065 0.3048)
			(end -0.67945 0.3048)
			(stroke
				(width 0.1)
				(type default)
			)
			(layer "F.Fab")
		)
		(fp_line
			(start 0.120396 0.2794)
			(end -0.12065 0.2794)
			(stroke
				(width 0.1)
				(type default)
			)
			(layer "F.Fab")
		)
		(fp_line
			(start 0.120396 0.3048)
			(end 0.120396 0.2794)
			(stroke
				(width 0.1)
				(type default)
			)
			(layer "F.Fab")
		)
		(fp_line
			(start 0.12065 -0.3048)
			(end 0.67945 -0.3048)
			(stroke
				(width 0.1)
				(type default)
			)
			(layer "F.Fab")
		)
		(fp_line
			(start 0.12065 -0.2794)
			(end 0.12065 -0.3048)
			(stroke
				(width 0.1)
				(type default)
			)
			(layer "F.Fab")
		)
		(fp_line
			(start 0.67945 -0.3048)
			(end 0.67945 0.3048)
			(stroke
				(width 0.1)
				(type default)
			)
			(layer "F.Fab")
		)
		(fp_line
			(start 0.67945 0.3048)
			(end 0.120396 0.3048)
			(stroke
				(width 0.1)
				(type default)
			)
			(layer "F.Fab")
		)
		(pad "1" smd circle
			(at -0.40005 0)
			(size 0 0)
			(layers "F.Cu" "F.Mask" "F.Paste")
			(net "M2_0_PEWAKE_R_N")
		)
		(pad "2" smd circle
			(at 0.40005 0)
			(size 0 0)
			(layers "F.Cu" "F.Mask" "F.Paste")
			(net "M2_0_PEWAKE_N")
		)
	)
)
